# BASEBOARD_FAB2 (Tioga Pass) — schematic netlist excerpt (pin names and nets, part order shuffled) for the footprints in the layout excerpt that follows; sources: Cadence DE-HDL packaged netlist, KiCad conversion of Wiwynn_Tioga_Pass_MB.brd

C4P6  CAP_A  22.0UF 4V 20% X6S  pkg 0603V  page 42 : A = PVCCIO_CPU0 ; B = GND
R1U18  RES  1.00K 1% CHIP  pkg 0402  page 164 : A = FM_BOARD_SKU_ID0 ; B = GND

(kicad_pcb
	(version 20260206)
	(generator "pcbnew")
	(generator_version "10.0")
	(general
		(thickness 1.6)
		(legacy_teardrops no)
	)
	(paper "A4")
	(title_block
		(title "Wiwynn_Tioga_Pass_MB.brd")
		(comment 1 "Tioga Pass / footprints 4279-4280 of 4770")
	)
	(layers
		(0 "F.Cu" signal "TOP")
		(4 "In1.Cu" signal "L2GND")
		(6 "In2.Cu" signal "L3")
		(8 "In3.Cu" signal "L4GND")
		(10 "In4.Cu" signal "L5")
		(12 "In5.Cu" signal "L6GND")
		(14 "In6.Cu" signal "L7VCC")
		(16 "In7.Cu" signal "L8VCC")
		(18 "In8.Cu" signal "L9GND")
		(20 "In9.Cu" signal "L10")
		(22 "In10.Cu" signal "L11GND")
		(24 "In11.Cu" signal "L12")
		(26 "In12.Cu" signal "L13GND")
		(2 "B.Cu" signal "BOTTOM")
		(9 "F.Adhes" user "F.Adhesive")
		(11 "B.Adhes" user "B.Adhesive")
		(13 "F.Paste" user "Package Geometry/Pastemask Top")
		(15 "B.Paste" user "Package Geometry/Pastemask Bottom")
		(5 "F.SilkS" user "Ref Des/Silkscreen Top")
		(7 "B.SilkS" user "Ref Des/Silkscreen Bottom")
		(1 "F.Mask" user "Board Geometry/Soldermask Top")
		(3 "B.Mask" user "Board Geometry/Soldermask Bottom")
		(17 "Dwgs.User" user "User.Drawings")
		(19 "Cmts.User" user "User.Comments")
		(21 "Eco1.User" user "User.Eco1")
		(23 "Eco2.User" user "User.Eco2")
		(25 "Edge.Cuts" user "Board Geometry/Outline")
		(27 "Margin" user)
		(31 "F.CrtYd" user "Package Geometry/Place Bound Top")
		(29 "B.CrtYd" user "Package Geometry/Place Bound Bottom")
		(35 "F.Fab" user "Ref Des/Assembly Top")
		(33 "B.Fab" user "Ref Des/Assembly Bottom")
	)
	(footprint ""
		(layer "B.Cu")
		(at 280.354024 -77.366114)
		(property "Reference" "C4P6"
			(at 0 0 0)
			(layer "B.SilkS")
			(hide yes)
			(effects
				(font
					(size 1.27 1.27)
				)
				(justify mirror)
			)
		)
		(property "Value" ""
			(at 0 0 0)
			(layer "B.Fab")
			(effects
				(font
					(size 1.27 1.27)
				)
				(justify mirror)
			)
		)
		(duplicate_pad_numbers_are_jumpers no)
		(fp_poly
			(pts
				(xy 0.4953 -0.2032) (xy -0.4953 -0.2032) (xy -0.4953 1.6002) (xy 0.4953 1.6002)
			)
			(stroke
				(width 0)
				(type default)
			)
			(fill no)
			(layer "B.CrtYd")
		)
		(fp_line
			(start -0.4953 -0.2032)
			(end -0.4953 1.6002)
			(stroke
				(width 0.1)
				(type default)
			)
			(layer "B.Fab")
		)
		(fp_line
			(start -0.4953 1.6002)
			(end 0.4953 1.6002)
			(stroke
				(width 0.1)
				(type default)
			)
			(layer "B.Fab")
		)
		(fp_line
			(start 0.4953 -0.2032)
			(end -0.4953 -0.2032)
			(stroke
				(width 0.1)
				(type default)
			)
			(layer "B.Fab")
		)
		(fp_line
			(start 0.4953 1.6002)
			(end 0.4953 -0.2032)
			(stroke
				(width 0.1)
				(type default)
			)
			(layer "B.Fab")
		)
		(pad "1" smd rect
			(at 0 0 180)
			(size 0.762 0.889)
			(layers "B.Cu" "B.Mask" "B.Paste")
			(net "PVCCIO_CPU0")
		)
		(pad "2" smd rect
			(at 0 1.397 180)
			(size 0.762 0.889)
			(layers "B.Cu" "B.Mask" "B.Paste")
			(net "GND")
		)
		(zone
			(layer "B.Cu")
			(hatch none 0.5)
			(connect_pads
				(clearance 0)
			)
			(min_thickness 0.25)
			(keepout
				(tracks not_allowed)
				(vias allowed)
				(pads allowed)
				(copperpour not_allowed)
				(footprints allowed)
			)
			(placement
				(enabled no)
				(sheetname "")
			)
			(fill
				(thermal_gap 0.5)
				(thermal_bridge_width 0.5)
				(island_removal_mode 0)
			)
			(polygon
				(pts
					(xy 280.735024 -76.921614) (xy 279.973024 -76.921614) (xy 279.973024 -76.413614) (xy 280.735024 -76.413614)
				)
			)
		)
	)
	(footprint ""
		(layer "B.Cu")
		(at 429.7172 -23.4188)
		(property "Reference" "R1U18"
			(at 0 0 0)
			(layer "B.SilkS")
			(hide yes)
			(effects
				(font
					(size 1.27 1.27)
				)
				(justify mirror)
			)
		)
		(property "Value" ""
			(at 0 0 0)
			(layer "B.Fab")
			(effects
				(font
					(size 1.27 1.27)
				)
				(justify mirror)
			)
		)
		(duplicate_pad_numbers_are_jumpers no)
		(fp_poly
			(pts
				(xy 0.2794 -0.1016) (xy -0.2794 -0.1016) (xy -0.2794 0.9906) (xy 0.2794 0.9906)
			)
			(stroke
				(width 0)
				(type default)
			)
			(fill no)
			(layer "B.CrtYd")
		)
		(fp_line
			(start -0.2794 -0.1016)
			(end 0.2794 -0.1016)
			(stroke
				(width 0.1)
				(type default)
			)
			(layer "B.Fab")
		)
		(fp_line
			(start -0.2794 0.9906)
			(end -0.2794 -0.1016)
			(stroke
				(width 0.1)
				(type default)
			)
			(layer "B.Fab")
		)
		(fp_line
			(start 0.2794 -0.1016)
			(end 0.2794 0.9906)
			(stroke
				(width 0.1)
				(type default)
			)
			(layer "B.Fab")
		)
		(fp_line
			(start 0.2794 0.9906)
			(end -0.2794 0.9906)
			(stroke
				(width 0.1)
				(type default)
			)
			(layer "B.Fab")
		)
		(pad "1" smd rect
			(at 0 0 180)
			(size 0.508 0.508)
			(layers "B.Cu" "B.Mask" "B.Paste")
			(net "FM_BOARD_SKU_ID0")
		)
		(pad "2" smd rect
			(at 0 0.889 180)
			(size 0.508 0.508)
			(layers "B.Cu" "B.Mask" "B.Paste")
			(net "GND")
		)
		(zone
			(layer "B.Cu")
			(hatch none 0.5)
			(connect_pads
				(clearance 0)
			)
			(min_thickness 0.25)
			(keepout
				(tracks allowed)
				(vias not_allowed)
				(pads allowed)
				(copperpour not_allowed)
				(footprints allowed)
			)
			(placement
				(enabled no)
				(sheetname "")
			)
			(fill
				(thermal_gap 0.5)
				(thermal_bridge_width 0.5)
				(island_removal_mode 0)
			)
			(polygon
				(pts
					(xy 429.9712 -23.1648) (xy 429.4632 -23.1648) (xy 429.4632 -22.7838) (xy 429.9712 -22.7838)
				)
			)
		)
		(zone
			(layer "B.Cu")
			(hatch none 0.5)
			(connect_pads
				(clearance 0)
			)
			(min_thickness 0.25)
			(keepout
				(tracks not_allowed)
				(vias allowed)
				(pads allowed)
				(copperpour not_allowed)
				(footprints allowed)
			)
			(placement
				(enabled no)
				(sheetname "")
			)
			(fill
				(thermal_gap 0.5)
				(thermal_bridge_width 0.5)
				(island_removal_mode 0)
			)
			(polygon
				(pts
					(xy 429.9712 -22.7838) (xy 429.4632 -22.7838) (xy 429.4632 -23.1648) (xy 429.9712 -23.1648)
				)
			)
		)
	)
)
